# BASEBOARD_FAB2 (Tioga Pass) — schematic netlist excerpt (pin names and nets, part order shuffled) for the footprints in the layout excerpt that follows; sources: Cadence DE-HDL packaged netlist, KiCad conversion of Wiwynn_Tioga_Pass_MB.brd

R8C26  RES  100.0 1% CHIP  pkg 0402  page 121 : A = A_1P8_3P3_RCOMP ; B = GND
R7F11  RES  6.19K 1% CHIP  pkg 0402  page 231 : A = VR_FB_PVPP_ABC ; B = AGND_PVPP_ABC
R1D2  RES  0.0 5% CHIP  pkg 0402  page 206 : A = SVID_VDIO_PVCCIN_CPU1 ; B = SVID_DIO0_CPU1_R

(kicad_pcb
	(version 20260206)
	(generator "pcbnew")
	(generator_version "10.0")
	(general
		(thickness 1.6)
		(legacy_teardrops no)
	)
	(paper "A4")
	(title_block
		(title "Wiwynn_Tioga_Pass_MB.brd")
		(comment 1 "Tioga Pass / footprints 1361-1363 of 4770")
	)
	(layers
		(0 "F.Cu" signal "TOP")
		(4 "In1.Cu" signal "L2GND")
		(6 "In2.Cu" signal "L3")
		(8 "In3.Cu" signal "L4GND")
		(10 "In4.Cu" signal "L5")
		(12 "In5.Cu" signal "L6GND")
		(14 "In6.Cu" signal "L7VCC")
		(16 "In7.Cu" signal "L8VCC")
		(18 "In8.Cu" signal "L9GND")
		(20 "In9.Cu" signal "L10")
		(22 "In10.Cu" signal "L11GND")
		(24 "In11.Cu" signal "L12")
		(26 "In12.Cu" signal "L13GND")
		(2 "B.Cu" signal "BOTTOM")
		(9 "F.Adhes" user "F.Adhesive")
		(11 "B.Adhes" user "B.Adhesive")
		(13 "F.Paste" user "Package Geometry/Pastemask Top")
		(15 "B.Paste" user "Package Geometry/Pastemask Bottom")
		(5 "F.SilkS" user "Ref Des/Silkscreen Top")
		(7 "B.SilkS" user "Ref Des/Silkscreen Bottom")
		(1 "F.Mask" user "Board Geometry/Soldermask Top")
		(3 "B.Mask" user "Board Geometry/Soldermask Bottom")
		(17 "Dwgs.User" user "User.Drawings")
		(19 "Cmts.User" user "User.Comments")
		(21 "Eco1.User" user "User.Eco1")
		(23 "Eco2.User" user "User.Eco2")
		(25 "Edge.Cuts" user "Board Geometry/Outline")
		(27 "Margin" user)
		(31 "F.CrtYd" user "Package Geometry/Place Bound Top")
		(29 "B.CrtYd" user "Package Geometry/Place Bound Bottom")
		(35 "F.Fab" user "Ref Des/Assembly Top")
		(33 "B.Fab" user "Ref Des/Assembly Bottom")
	)
	(footprint ""
		(layer "F.Cu")
		(at 389.128 -88.2015)
		(property "Reference" "R8C26"
			(at 0 0 0)
			(layer "F.SilkS")
			(hide yes)
			(effects
				(font
					(size 1.27 1.27)
				)
			)
		)
		(property "Value" ""
			(at 0 0 0)
			(layer "F.Fab")
			(effects
				(font
					(size 1.27 1.27)
				)
			)
		)
		(duplicate_pad_numbers_are_jumpers no)
		(fp_poly
			(pts
				(xy -0.2794 -0.1016) (xy 0.2794 -0.1016) (xy 0.2794 0.9906) (xy -0.2794 0.9906)
			)
			(stroke
				(width 0)
				(type default)
			)
			(fill no)
			(layer "F.CrtYd")
		)
		(fp_line
			(start -0.2794 -0.1016)
			(end -0.2794 0.9906)
			(stroke
				(width 0.1)
				(type default)
			)
			(layer "F.Fab")
		)
		(fp_line
			(start -0.2794 0.9906)
			(end 0.2794 0.9906)
			(stroke
				(width 0.1)
				(type default)
			)
			(layer "F.Fab")
		)
		(fp_line
			(start 0.2794 -0.1016)
			(end -0.2794 -0.1016)
			(stroke
				(width 0.1)
				(type default)
			)
			(layer "F.Fab")
		)
		(fp_line
			(start 0.2794 0.9906)
			(end 0.2794 -0.1016)
			(stroke
				(width 0.1)
				(type default)
			)
			(layer "F.Fab")
		)
		(pad "1" smd rect
			(at 0 0)
			(size 0.508 0.508)
			(layers "F.Cu" "F.Mask" "F.Paste")
			(net "A_1P8_3P3_RCOMP")
		)
		(pad "2" smd rect
			(at 0 0.889)
			(size 0.508 0.508)
			(layers "F.Cu" "F.Mask" "F.Paste")
			(net "GND")
		)
		(zone
			(layer "F.Cu")
			(hatch none 0.5)
			(connect_pads
				(clearance 0)
			)
			(min_thickness 0.25)
			(keepout
				(tracks allowed)
				(vias not_allowed)
				(pads allowed)
				(copperpour not_allowed)
				(footprints allowed)
			)
			(placement
				(enabled no)
				(sheetname "")
			)
			(fill
				(thermal_gap 0.5)
				(thermal_bridge_width 0.5)
				(island_removal_mode 0)
			)
			(polygon
				(pts
					(xy 388.874 -87.9475) (xy 389.382 -87.9475) (xy 389.382 -87.5665) (xy 388.874 -87.5665)
				)
			)
		)
		(zone
			(layer "F.Cu")
			(hatch none 0.5)
			(connect_pads
				(clearance 0)
			)
			(min_thickness 0.25)
			(keepout
				(tracks not_allowed)
				(vias allowed)
				(pads allowed)
				(copperpour not_allowed)
				(footprints allowed)
			)
			(placement
				(enabled no)
				(sheetname "")
			)
			(fill
				(thermal_gap 0.5)
				(thermal_bridge_width 0.5)
				(island_removal_mode 0)
			)
			(polygon
				(pts
					(xy 388.874 -87.5665) (xy 389.382 -87.5665) (xy 389.382 -87.9475) (xy 388.874 -87.9475)
				)
			)
		)
	)
	(footprint ""
		(layer "F.Cu")
		(at 337.439 -24.1554 90)
		(property "Reference" "R7F11"
			(at 0 0 90)
			(layer "F.SilkS")
			(hide yes)
			(effects
				(font
					(size 1.27 1.27)
				)
			)
		)
		(property "Value" ""
			(at 0 0 90)
			(layer "F.Fab")
			(effects
				(font
					(size 1.27 1.27)
				)
			)
		)
		(duplicate_pad_numbers_are_jumpers no)
		(fp_rect
			(start -0.2794 0.9906)
			(end 0.2794 -0.1016)
			(stroke
				(width 0)
				(type default)
			)
			(fill no)
			(layer "F.CrtYd")
		)
		(fp_line
			(start 0.2794 -0.1016)
			(end -0.2794 -0.1016)
			(stroke
				(width 0.1)
				(type default)
			)
			(layer "F.Fab")
		)
		(fp_line
			(start -0.2794 -0.1016)
			(end -0.2794 0.9906)
			(stroke
				(width 0.1)
				(type default)
			)
			(layer "F.Fab")
		)
		(fp_line
			(start 0.2794 0.9906)
			(end 0.2794 -0.1016)
			(stroke
				(width 0.1)
				(type default)
			)
			(layer "F.Fab")
		)
		(fp_line
			(start -0.2794 0.9906)
			(end 0.2794 0.9906)
			(stroke
				(width 0.1)
				(type default)
			)
			(layer "F.Fab")
		)
		(pad "1" smd rect
			(at 0 0 90)
			(size 0.508 0.508)
			(layers "F.Cu" "F.Mask" "F.Paste")
			(net "VR_FB_PVPP_ABC")
		)
		(pad "2" smd rect
			(at 0 0.889 90)
			(size 0.508 0.508)
			(layers "F.Cu" "F.Mask" "F.Paste")
			(net "AGND_PVPP_ABC")
		)
		(zone
			(layer "F.Cu")
			(hatch none 0.5)
			(connect_pads
				(clearance 0)
			)
			(min_thickness 0.25)
			(keepout
				(tracks not_allowed)
				(vias allowed)
				(pads allowed)
				(copperpour not_allowed)
				(footprints allowed)
			)
			(placement
				(enabled no)
				(sheetname "")
			)
			(fill
				(thermal_gap 0.5)
				(thermal_bridge_width 0.5)
				(island_removal_mode 0)
			)
			(polygon
				(pts
					(xy 338.074 -23.9014) (xy 338.074 -24.4094) (xy 337.693 -24.4094) (xy 337.693 -23.9014)
				)
			)
		)
		(zone
			(layer "F.Cu")
			(hatch none 0.5)
			(connect_pads
				(clearance 0)
			)
			(min_thickness 0.25)
			(keepout
				(tracks allowed)
				(vias not_allowed)
				(pads allowed)
				(copperpour not_allowed)
				(footprints allowed)
			)
			(placement
				(enabled no)
				(sheetname "")
			)
			(fill
				(thermal_gap 0.5)
				(thermal_bridge_width 0.5)
				(island_removal_mode 0)
			)
			(polygon
				(pts
					(xy 338.074 -23.9014) (xy 338.074 -24.4094) (xy 337.693 -24.4094) (xy 337.693 -23.9014)
				)
			)
		)
	)
	(footprint ""
		(layer "F.Cu")
		(at 18.288 -87.7062)
		(property "Reference" "R1D2"
			(at 0 0 0)
			(layer "F.SilkS")
			(hide yes)
			(effects
				(font
					(size 1.27 1.27)
				)
			)
		)
		(property "Value" ""
			(at 0 0 0)
			(layer "F.Fab")
			(effects
				(font
					(size 1.27 1.27)
				)
			)
		)
		(duplicate_pad_numbers_are_jumpers no)
		(fp_rect
			(start -0.2794 0.9906)
			(end 0.2794 -0.1016)
			(stroke
				(width 0)
				(type default)
			)
			(fill no)
			(layer "F.CrtYd")
		)
		(fp_line
			(start -0.2794 -0.1016)
			(end -0.2794 0.9906)
			(stroke
				(width 0.1)
				(type default)
			)
			(layer "F.Fab")
		)
		(fp_line
			(start -0.2794 0.9906)
			(end 0.2794 0.9906)
			(stroke
				(width 0.1)
				(type default)
			)
			(layer "F.Fab")
		)
		(fp_line
			(start 0.2794 -0.1016)
			(end -0.2794 -0.1016)
			(stroke
				(width 0.1)
				(type default)
			)
			(layer "F.Fab")
		)
		(fp_line
			(start 0.2794 0.9906)
			(end 0.2794 -0.1016)
			(stroke
				(width 0.1)
				(type default)
			)
			(layer "F.Fab")
		)
		(pad "1" smd rect
			(at 0 0)
			(size 0.508 0.508)
			(layers "F.Cu" "F.Mask" "F.Paste")
			(net "SVID_VDIO_PVCCIN_CPU1")
		)
		(pad "2" smd rect
			(at 0 0.889)
			(size 0.508 0.508)
			(layers "F.Cu" "F.Mask" "F.Paste")
			(net "SVID_DIO0_CPU1_R")
		)
		(zone
			(layer "F.Cu")
			(hatch none 0.5)
			(connect_pads
				(clearance 0)
			)
			(min_thickness 0.25)
			(keepout
				(tracks not_allowed)
				(vias allowed)
				(pads allowed)
				(copperpour not_allowed)
				(footprints allowed)
			)
			(placement
				(enabled no)
				(sheetname "")
			)
			(fill
				(thermal_gap 0.5)
				(thermal_bridge_width 0.5)
				(island_removal_mode 0)
			)
			(polygon
				(pts
					(xy 18.034 -87.0712) (xy 18.542 -87.0712) (xy 18.542 -87.4522) (xy 18.034 -87.4522)
				)
			)
		)
		(zone
			(layer "F.Cu")
			(hatch none 0.5)
			(connect_pads
				(clearance 0)
			)
			(min_thickness 0.25)
			(keepout
				(tracks allowed)
				(vias not_allowed)
				(pads allowed)
				(copperpour not_allowed)
				(footprints allowed)
			)
			(placement
				(enabled no)
				(sheetname "")
			)
			(fill
				(thermal_gap 0.5)
				(thermal_bridge_width 0.5)
				(island_removal_mode 0)
			)
			(polygon
				(pts
					(xy 18.034 -87.0712) (xy 18.542 -87.0712) (xy 18.542 -87.4522) (xy 18.034 -87.4522)
				)
			)
		)
	)
)
